# S9S_MB_2U (Grand Teton) — schematic netlist excerpt (pin names and nets, part order shuffled) for the footprints in the layout excerpt that follows; sources: Cadence DE-HDL packaged netlist, KiCad conversion of 03242023_DA0F0TMBIJ0_F0T_Motherboard_J_brd_V01_OCP.brd

PR4245  Q_RES  0 5% CHIP  pkg 0402LF  page 292 : A = NC_PVCCINFAON_CPU1_ACSP6 ; B = GND
PR3805  Q_RES  160K 1% EMPTY  pkg 0402LF  page 162 : A = P12V_AUX ; B = P12V_OCP_UV_2

(kicad_pcb
	(version 20260206)
	(generator "pcbnew")
	(generator_version "10.0")
	(general
		(thickness 1.6)
		(legacy_teardrops no)
	)
	(paper "A4")
	(title_block
		(title "03242023_DA0F0TMBIJ0_F0T_Motherboard_J_brd_V01_OCP.brd")
		(comment 1 "Grand Teton / footprints 2030-2031 of 6105")
	)
	(layers
		(0 "F.Cu" signal "TOP")
		(4 "In1.Cu" signal "GND")
		(6 "In2.Cu" signal "IN1")
		(8 "In3.Cu" signal "GND1")
		(10 "In4.Cu" signal "IN2")
		(12 "In5.Cu" signal "GND2")
		(14 "In6.Cu" signal "IN3")
		(16 "In7.Cu" signal "GND3")
		(18 "In8.Cu" signal "VCC")
		(20 "In9.Cu" signal "VCC1")
		(22 "In10.Cu" signal "GND4")
		(24 "In11.Cu" signal "IN4")
		(26 "In12.Cu" signal "GND5")
		(28 "In13.Cu" signal "IN5")
		(30 "In14.Cu" signal "GND6")
		(32 "In15.Cu" signal "IN6")
		(34 "In16.Cu" signal "GND7")
		(2 "B.Cu" signal "BOTTOM")
		(9 "F.Adhes" user "F.Adhesive")
		(11 "B.Adhes" user "B.Adhesive")
		(13 "F.Paste" user "Package Geometry/Pastemask Top")
		(15 "B.Paste" user "Package Geometry/Pastemask Bottom")
		(5 "F.SilkS" user "Ref Des/Silkscreen Top")
		(7 "B.SilkS" user "Ref Des/Silkscreen Bottom")
		(1 "F.Mask" user "Board Geometry/Soldermask Top")
		(3 "B.Mask" user "Board Geometry/Soldermask Bottom")
		(17 "Dwgs.User" user "User.Drawings")
		(19 "Cmts.User" user "User.Comments")
		(21 "Eco1.User" user "User.Eco1")
		(23 "Eco2.User" user "User.Eco2")
		(25 "Edge.Cuts" user "Board Geometry/Outline")
		(27 "Margin" user)
		(31 "F.CrtYd" user "Package Geometry/Place Bound Top")
		(29 "B.CrtYd" user "Package Geometry/Place Bound Bottom")
		(35 "F.Fab" user "Ref Des/Assembly Top")
		(33 "B.Fab" user "Ref Des/Assembly Bottom")
	)
	(footprint ""
		(layer "F.Cu")
		(at 75.416918 -18.164302)
		(property "Reference" "PR3805"
			(at 0 0 0)
			(layer "F.SilkS")
			(hide yes)
			(effects
				(font
					(size 1.27 1.27)
				)
			)
		)
		(property "Value" ""
			(at 0 0 0)
			(layer "F.Fab")
			(effects
				(font
					(size 1.27 1.27)
				)
			)
		)
		(duplicate_pad_numbers_are_jumpers no)
		(fp_line
			(start -0.7874 -0.4064)
			(end 0.7874 -0.4064)
			(stroke
				(width 0.1524)
				(type default)
			)
			(layer "F.SilkS")
		)
		(fp_line
			(start -0.7874 0.4064)
			(end -0.7874 -0.4064)
			(stroke
				(width 0.1524)
				(type default)
			)
			(layer "F.SilkS")
		)
		(fp_line
			(start 0.7874 -0.4064)
			(end 0.7874 0.4064)
			(stroke
				(width 0.1524)
				(type default)
			)
			(layer "F.SilkS")
		)
		(fp_line
			(start 0.7874 0.4064)
			(end -0.7874 0.4064)
			(stroke
				(width 0.1524)
				(type default)
			)
			(layer "F.SilkS")
		)
		(fp_line
			(start -0.67945 -0.305054)
			(end -0.12065 -0.305054)
			(stroke
				(width 0.1)
				(type default)
			)
			(layer "F.Fab")
		)
		(fp_line
			(start -0.67945 0.3048)
			(end -0.67945 -0.305054)
			(stroke
				(width 0.1)
				(type default)
			)
			(layer "F.Fab")
		)
		(fp_line
			(start -0.12065 -0.305054)
			(end -0.12065 -0.2794)
			(stroke
				(width 0.1)
				(type default)
			)
			(layer "F.Fab")
		)
		(fp_line
			(start -0.12065 -0.2794)
			(end 0.12065 -0.2794)
			(stroke
				(width 0.1)
				(type default)
			)
			(layer "F.Fab")
		)
		(fp_line
			(start -0.12065 0.2794)
			(end -0.12065 0.3048)
			(stroke
				(width 0.1)
				(type default)
			)
			(layer "F.Fab")
		)
		(fp_line
			(start -0.12065 0.3048)
			(end -0.67945 0.3048)
			(stroke
				(width 0.1)
				(type default)
			)
			(layer "F.Fab")
		)
		(fp_line
			(start 0.120396 0.2794)
			(end -0.12065 0.2794)
			(stroke
				(width 0.1)
				(type default)
			)
			(layer "F.Fab")
		)
		(fp_line
			(start 0.120396 0.3048)
			(end 0.120396 0.2794)
			(stroke
				(width 0.1)
				(type default)
			)
			(layer "F.Fab")
		)
		(fp_line
			(start 0.12065 -0.3048)
			(end 0.67945 -0.3048)
			(stroke
				(width 0.1)
				(type default)
			)
			(layer "F.Fab")
		)
		(fp_line
			(start 0.12065 -0.2794)
			(end 0.12065 -0.3048)
			(stroke
				(width 0.1)
				(type default)
			)
			(layer "F.Fab")
		)
		(fp_line
			(start 0.67945 -0.3048)
			(end 0.67945 0.3048)
			(stroke
				(width 0.1)
				(type default)
			)
			(layer "F.Fab")
		)
		(fp_line
			(start 0.67945 0.3048)
			(end 0.120396 0.3048)
			(stroke
				(width 0.1)
				(type default)
			)
			(layer "F.Fab")
		)
		(pad "1" smd circle
			(at -0.40005 0)
			(size 0 0)
			(layers "F.Cu" "F.Mask" "F.Paste")
			(net "P12V_AUX")
		)
		(pad "2" smd circle
			(at 0.40005 0)
			(size 0 0)
			(layers "F.Cu" "F.Mask" "F.Paste")
			(net "P12V_OCP_UV_2")
		)
	)
	(footprint ""
		(layer "F.Cu")
		(at 29.22524 -137.978388 90)
		(property "Reference" "PR4245"
			(at 0 0 90)
			(layer "F.SilkS")
			(hide yes)
			(effects
				(font
					(size 1.27 1.27)
				)
			)
		)
		(property "Value" ""
			(at 0 0 90)
			(layer "F.Fab")
			(effects
				(font
					(size 1.27 1.27)
				)
			)
		)
		(duplicate_pad_numbers_are_jumpers no)
		(fp_line
			(start 0.7874 -0.4064)
			(end 0.7874 0.4064)
			(stroke
				(width 0.1524)
				(type default)
			)
			(layer "F.SilkS")
		)
		(fp_line
			(start -0.7874 -0.4064)
			(end 0.7874 -0.4064)
			(stroke
				(width 0.1524)
				(type default)
			)
			(layer "F.SilkS")
		)
		(fp_line
			(start 0.7874 0.4064)
			(end -0.7874 0.4064)
			(stroke
				(width 0.1524)
				(type default)
			)
			(layer "F.SilkS")
		)
		(fp_line
			(start -0.7874 0.4064)
			(end -0.7874 -0.4064)
			(stroke
				(width 0.1524)
				(type default)
			)
			(layer "F.SilkS")
		)
		(fp_line
			(start -0.12065 -0.305054)
			(end -0.12065 -0.2794)
			(stroke
				(width 0.1)
				(type default)
			)
			(layer "F.Fab")
		)
		(fp_line
			(start -0.67945 -0.305054)
			(end -0.12065 -0.305054)
			(stroke
				(width 0.1)
				(type default)
			)
			(layer "F.Fab")
		)
		(fp_line
			(start 0.67945 -0.3048)
			(end 0.67945 0.3048)
			(stroke
				(width 0.1)
				(type default)
			)
			(layer "F.Fab")
		)
		(fp_line
			(start 0.12065 -0.3048)
			(end 0.67945 -0.3048)
			(stroke
				(width 0.1)
				(type default)
			)
			(layer "F.Fab")
		)
		(fp_line
			(start 0.12065 -0.2794)
			(end 0.12065 -0.3048)
			(stroke
				(width 0.1)
				(type default)
			)
			(layer "F.Fab")
		)
		(fp_line
			(start -0.12065 -0.2794)
			(end 0.12065 -0.2794)
			(stroke
				(width 0.1)
				(type default)
			)
			(layer "F.Fab")
		)
		(fp_line
			(start 0.120396 0.2794)
			(end -0.12065 0.2794)
			(stroke
				(width 0.1)
				(type default)
			)
			(layer "F.Fab")
		)
		(fp_line
			(start -0.12065 0.2794)
			(end -0.12065 0.3048)
			(stroke
				(width 0.1)
				(type default)
			)
			(layer "F.Fab")
		)
		(fp_line
			(start 0.67945 0.3048)
			(end 0.120396 0.3048)
			(stroke
				(width 0.1)
				(type default)
			)
			(layer "F.Fab")
		)
		(fp_line
			(start 0.120396 0.3048)
			(end 0.120396 0.2794)
			(stroke
				(width 0.1)
				(type default)
			)
			(layer "F.Fab")
		)
		(fp_line
			(start -0.12065 0.3048)
			(end -0.67945 0.3048)
			(stroke
				(width 0.1)
				(type default)
			)
			(layer "F.Fab")
		)
		(fp_line
			(start -0.67945 0.3048)
			(end -0.67945 -0.305054)
			(stroke
				(width 0.1)
				(type default)
			)
			(layer "F.Fab")
		)
		(pad "1" smd circle
			(at -0.40005 0 90)
			(size 0 0)
			(layers "F.Cu" "F.Mask" "F.Paste")
			(net "NC_PVCCINFAON_CPU1_ACSP6")
		)
		(pad "2" smd circle
			(at 0.40005 0 90)
			(size 0 0)
			(layers "F.Cu" "F.Mask" "F.Paste")
			(net "GND")
		)
	)
)
